# S9S_MB_2U (Grand Teton) — schematic parts with pin connectivity, parts 5880–5880 of 6093; source: Cadence DE-HDL packaged netlist (pstxprt.dat, pstxnet.dat, pstchip.dat)

U2  SOCKET4677_AZIF0045P001C01CS  SOCKET4677_AZIF0045-P001C01CS IO  pkg SOCKET4677_82X64-5XA_H466  page 13  (pins 2283-2608 of 4677)
  CW50  DDR6_ALERT_N  IN  = M_G_CPU0_ALERT_N
  CW52  VCCD_HV23  POWER  = PVCCD_HV_CPU0
  CW54  VCCD_HV24  POWER  = PVCCD_HV_CPU0
  CW56  VCCD_HV25  POWER  = PVCCD_HV_CPU0
  CW58  RSVD149  BI  = NC_CPU0_VIEWPIN_GNR1
  CW60  SOCKET_ID0  IN  = PU_CPU0_SOCKET_ID0
  CW62  VCCINFAON52  POWER  = PVCCINFAON_CPU0
  CW64  VCCINFAON55  POWER  = PVCCINFAON_CPU0
  CW66  VCCINFAON21  POWER  = PVCCINFAON_CPU0
  CW68  RSVD150  BI  = NC_CPU0_RSVD<144>
  CW70  VSS595  POWER  = GND
  CW72  VSS840  POWER  = GND
  CW74  UPI3_TX_DP22  OUT  = NC
  CW76  UPI3_TX_DN12  OUT  = NC
  CW78  VSS843  POWER  = GND
  CW80  UPI3_RX_DN19  IN  = GND
  CW82  UPI3_RX_DP17  IN  = GND
  CW84  VSS846  POWER  = GND
  CW86  PE3_TX_DP13  OUT  = P5E_CPU0_PE3_TX_DP<13>
  CW88  VSS848  POWER  = GND
  CW90  PE3_RX_DP14  IN  = P5E_CPU0_PE3_RX_DP<14>
  CY2  UPI1_RX_DN14  IN  = UPI_CPU1_CPU0_P0P1_DN<14>
  CY4  VSS611  POWER  = GND
  CY6  UPI1_TX_DN13  OUT  = UPI_CPU0_CPU1_P1P0_DP<13>
  CY8  VSS860  POWER  = GND
  CY10  PE2_RX_DN1  IN  = P5E_CPU0_PE2_RX_DN<1>
  CY12  VSS851  POWER  = GND
  CY14  PE2_TX_DP2  OUT  = P5E_CPU0_PE2_TX_DP<2>
  CY16  VSS852  POWER  = GND
  CY18  VSS853  POWER  = GND
  CY20  CD_INIT_ERROR  OUT  = FM_S3M_CPU0_CPLD_CRC_ERROR
  CY22  TEST_5  BI  = PD_JTAG_CPU0_PLD_TCK
  CY24  RSVD151  BI  = NC_CPU0_DDR45_VIEWDIG0
  CY26  VSS854  POWER  = GND
  CY28  BCLK1_DN  IN  = CLK_100M_DB2000_CPU0_BCLK1_DN
  CY30  VSS855  POWER  = GND
  CY32  XTAL_CLK_DP  IN  = CLK_25M_NSSC_CPU0_DP
  CY34  VCCD_HV26  POWER  = PVCCD_HV_CPU0
  CY36  VCCD_HV27  POWER  = PVCCD_HV_CPU0
  CY38  RSVD152  BI  = NC_CPU0_DDR45_VIEWDIG1
  CY40  PMDOWN_PCH  BI  = H_CPU0_PMDOWN_PCH_R2
  CY42  DDR45_RESET_N  OUT  = RST_CPU0_DRAM_EF_N
  CY44  DDR45_DRAM_PWR_OK  IN  = PWRGD_DRAMPWRGD_CPU0_EF_LVC1_R
  CY47  DDR4_ALERT_N  IN  = M_E_CPU0_ALERT_N
  CY49  RSVD153  BI  = NC_CPU0_DDR67_VIEWDIG1
  CY51  DDR7_ALERT_N  IN  = M_H_CPU0_ALERT_N
  CY53  VCCD_HV28  POWER  = PVCCD_HV_CPU0
  CY55  DDR67_RESET_N  OUT  = RST_CPU0_DRAM_GH_N
  CY57  RSVD154  BI  = NC_CPU0_VIEWPIN_GNR3
  CY59  LEGACY_SKT  IN  = PU_CPU0_LEGACY_SKT
  CY61  SOCKET_ID1  IN  = PU_CPU0_SOCKET_ID1
  CY63  VSS856  POWER  = GND
  CY65  VCCINFAON22  POWER  = PVCCINFAON_CPU0
  CY67  VCCINFAON23  POWER  = PVCCINFAON_CPU0
  CY69  RSVD155  BI  = NC_UART_IBL_CPU0_RXD
  CY71  RSVD156  BI  = NC_UART_IBL_CPU0_RTS
  CY73  VSS858  POWER  = GND
  CY75  VCCFA_EHV_FIVRA42  POWER  = PVCCFA_EHV_FIVRA_CPU0
  CY77  VSS859  POWER  = GND
  CY79  VCCFA_EHV_FIVRA43  POWER  = PVCCFA_EHV_FIVRA_CPU0
  CY81  VSS862  POWER  = GND
  CY83  VSS863  POWER  = GND
  CY85  VCCFA_EHV_FIVRA44  POWER  = PVCCFA_EHV_FIVRA_CPU0
  CY87  PE3_TX_DN12  OUT  = P5E_CPU0_PE3_TX_DN<12>
  CY89  VCCFA_EHV_FIVRA45  POWER  = PVCCFA_EHV_FIVRA_CPU0
  CY91  PE3_RX_DP13  IN  = P5E_CPU0_PE3_RX_DP<13>
  D4  RSVD157  BI  = NC_XTAL_CPU0_25M_OUT
  D6  VSS899  POWER  = GND
  D8  VSS663  POWER  = GND
  D10  VSS864  POWER  = GND
  D12  VSS865  POWER  = GND
  D14  VSS866  POWER  = GND
  D16  VSS868  POWER  = GND
  D18  VSS869  POWER  = GND
  D20  VSS871  POWER  = GND
  D22  VSS873  POWER  = GND
  D24  VSS874  POWER  = GND
  D26  VSS875  POWER  = GND
  D28  VSS876  POWER  = GND
  D30  VSS877  POWER  = GND
  D32  VSS878  POWER  = GND
  D34  VSS879  POWER  = GND
  D36  VSS881  POWER  = GND
  D38  VSS884  POWER  = GND
  D40  VSS885  POWER  = GND
  D42  VSS886  POWER  = GND
  D44  VSS888  POWER  = GND
  D47  VSS889  POWER  = GND
  D49  VSS891  POWER  = GND
  D51  VSS892  POWER  = GND
  D53  VSS895  POWER  = GND
  D55  VSS896  POWER  = GND
  D57  VSS897  POWER  = GND
  D59  VSS898  POWER  = GND
  D61  VSS900  POWER  = GND
  D63  VSS657  POWER  = GND
  D65  VSS658  POWER  = GND
  D67  VSS659  POWER  = GND
  D69  VSS901  POWER  = GND
  D71  VSS902  POWER  = GND
  D73  DDR0_SA_DQ18  BI  = M_A_CPU0_SA_DQ<18>
  D75  DDR0_SA_DQ5  BI  = M_A_CPU0_SA_DQ<5>
  D77  DDR0_SA_DQS_DP0  BI  = M_A_CPU0_SA_DQS_DP<0>
  D79  VSS662  POWER  = GND
  D81  VSS906  POWER  = GND
  D83  VSS907  POWER  = GND
  D85  UPI2_TX_DP0  OUT  = UPI_CPU0_CPU1_P2P2_DP<23>
  D87  UPI2_TX_DN2  OUT  = UPI_CPU0_CPU1_P2P2_DN<21>
  DA1  UPI1_RX_DP13  IN  = UPI_CPU1_CPU0_P0P1_DP<13>
  DA3  VCCINFAON56  POWER  = PVCCINFAON_CPU0
  DA5  UPI1_TX_DN12  OUT  = UPI_CPU0_CPU1_P1P0_DP<12>
  DA7  VCCINFAON57  POWER  = PVCCINFAON_CPU0
  DA9  PE2_RX_DN2  IN  = P5E_CPU0_PE2_RX_DN<2>
  DA11  VCCINFAON24  POWER  = PVCCINFAON_CPU0
  DA13  PE2_TX_DN2  OUT  = P5E_CPU0_PE2_TX_DN<2>
  DA15  VCCINFAON25  POWER  = PVCCINFAON_CPU0
  DA17  DDR7_SB_DQ29  BI  = M_H_CPU0_SB_DQ<29>
  DA19  VSS910  POWER  = GND
  DA21  VCCINFAON53  POWER  = PVCCINFAON_CPU0
  DA23  VSS911  POWER  = GND
  DA25  VSS912  POWER  = GND
  DA27  BCLK3_DP  IN  = CLK_100M_DB2000_CPU0_BCLK3_DP
  DA29  VSS913  POWER  = GND
  DA31  VSS914  POWER  = GND
  DA33  VSS915  POWER  = GND
  DA35  VSS916  POWER  = GND
  DA37  VSS917  POWER  = GND
  DA39  PMSYNC_PCH  BI  = H_CPU0_PMSYNC_PCH
  DA41  VSS918  POWER  = GND
  DA43  VSS679  POWER  = GND
  DA45  RSVD158  BI  = NC_CPU0_DDR67_VIEWDIG0
  DA48  VSS919  POWER  = GND
  DA50  VSS920  POWER  = GND
  DA52  PROCDIS_N  IN  = TP_CPU0_PROCDIS_COD_GTL_N
  DA54  VSS921  POWER  = GND
  DA56  VSS922  POWER  = GND
  DA58  VSS923  POWER  = GND
  DA60  VSS924  POWER  = GND
  DA62  VSS925  POWER  = GND
  DA64  VCCINFAON26  POWER  = PVCCINFAON_CPU0
  DA66  VSS926  POWER  = GND
  DA68  VSS690  POWER  = GND
  DA70  RSVD159  BI  = TP_CPU0_SPARE4
  DA72  VSS927  POWER  = GND
  DA74  VSS928  POWER  = GND
  DA76  UPI3_TX_DP12  OUT  = NC
  DA78  UPI3_RX_DN23  IN  = GND
  DA80  VSS929  POWER  = GND
  DA82  VSS930  POWER  = GND
  DA84  VSS931  POWER  = GND
  DA86  PE3_TX_DP12  OUT  = P5E_CPU0_PE3_TX_DP<12>
  DA88  VSS932  POWER  = GND
  DA90  PE3_RX_DN13  IN  = P5E_CPU0_PE3_RX_DN<13>
  DB2  UPI1_RX_DN13  IN  = UPI_CPU1_CPU0_P0P1_DN<13>
  DB4  VSS939  POWER  = GND
  DB6  UPI1_TX_DP12  OUT  = UPI_CPU0_CPU1_P1P0_DN<12>
  DB8  VSS947  POWER  = GND
  DB10  PE2_RX_DP2  IN  = P5E_CPU0_PE2_RX_DP<2>
  DB12  VSS933  POWER  = GND
  DB14  PE2_TX_DN3  OUT  = P5E_CPU0_PE2_TX_DN<3>
  DB16  VSS699  POWER  = GND
  DB18  DDR7_SB_DQS_DN3  BI  = M_H_CPU0_SB_DQS_DN<3>
  DB20  VSS700  POWER  = GND
  DB22  VSS935  POWER  = GND
  DB24  DDR7_SB_DQS_DP1  BI  = M_H_CPU0_SB_DQS_DP<1>
  DB26  VSS702  POWER  = GND
  DB28  VSS936  POWER  = GND
  DB30  DDR7_SB_DQS_DP0  BI  = M_H_CPU0_SB_DQS_DP<0>
  DB32  VSS937  POWER  = GND
  DB34  VSS705  POWER  = GND
  DB36  DDR7_SB_DQS_DP9  BI  = M_H_CPU0_SB_DQS_DP<9>
  DB38  VSS938  POWER  = GND
  DB40  VSS940  POWER  = GND
  DB42  DDR7_CLK_DP1  OUT  = M_H_CPU0_CLK_DP<1>
  DB44  VSS709  POWER  = GND
  DB47  VSS941  POWER  = GND
  DB49  DDR7_SA_CA0  OUT  = M_H_CPU0_SA_CA<0>
  DB51  VSS711  POWER  = GND
  DB53  VSS712  POWER  = GND
  DB55  DDR7_SA_DQS_DP4  BI  = M_H_CPU0_SA_DQS_DP<4>
  DB57  VSS942  POWER  = GND
  DB59  VSS714  POWER  = GND
  DB61  DDR7_SA_DQS_DP3  BI  = M_H_CPU0_SA_DQS_DP<3>
  DB63  VSS715  POWER  = GND
  DB65  VSS943  POWER  = GND
  DB67  DDR7_SA_DQS_DP2  BI  = M_H_CPU0_SA_DQS_DP<2>
  DB69  VSS717  POWER  = GND
  DB71  VSS944  POWER  = GND
  DB73  DDR7_SA_DQS_DN1  BI  = M_H_CPU0_SA_DQS_DN<1>
  DB75  VSS719  POWER  = GND
  DB77  VSS946  POWER  = GND
  DB79  UPI3_RX_DP23  IN  = GND
  DB81  UPI3_RX_DN15  IN  = GND
  DB83  UPI3_RX_DP14  IN  = GND
  DB85  PE3_TX_DN11  OUT  = P5E_CPU0_PE3_TX_DN<11>
  DB87  VSS948  POWER  = GND
  DB89  PE3_RX_DN12  IN  = P5E_CPU0_PE3_RX_DN<12>
  DB91  VSS723  POWER  = GND
  DC1  VSS724  POWER  = GND
  DC3  UPI1_RX_DP12  IN  = UPI_CPU1_CPU0_P0P1_DN<12>
  DC5  VSS953  POWER  = GND
  DC7  UPI1_TX_DP11  OUT  = UPI_CPU0_CPU1_P1P0_DN<11>
  DC9  VSS963  POWER  = GND
  DC11  PE2_RX_DP3  IN  = P5E_CPU0_PE2_RX_DP<3>
  DC13  VSS725  POWER  = GND
  DC15  PE2_TX_DP3  OUT  = P5E_CPU0_PE2_TX_DP<3>
  DC17  DDR7_SB_DQ31  BI  = M_H_CPU0_SB_DQ<31>
  DC19  DDR7_SB_DQ25  BI  = M_H_CPU0_SB_DQ<25>
  DC21  VSS726  POWER  = GND
  DC23  DDR7_SB_DQ12  BI  = M_H_CPU0_SB_DQ<12>
  DC25  DDR7_SB_DQ9  BI  = M_H_CPU0_SB_DQ<9>
  DC27  VSS949  POWER  = GND
  DC29  DDR7_SB_DQ4  BI  = M_H_CPU0_SB_DQ<4>
  DC31  DDR7_SB_DQ1  BI  = M_H_CPU0_SB_DQ<1>
  DC33  VSS950  POWER  = GND
  DC35  DDR7_SB_ECC0  BI  = M_H_CPU0_SB_CB<0>
  DC37  DDR7_SB_ECC7  BI  = M_H_CPU0_SB_CB<7>
  DC39  VSS951  POWER  = GND
  DC41  DDR7_SA_CA6  OUT  = M_H_CPU0_SA_CA<6>
  DC43  DDR4_A_RSP1  IN  = M_E_CPU0_SA_RSP<1>
  DC45  VSS952  POWER  = GND
  DC48  DDR7_SA_CA2  OUT  = M_H_CPU0_SA_CA<2>
  DC50  DDR7_SA_CS_N3  OUT  = M_H_CPU0_SA_CS_N<3>
  DC52  VSS735  POWER  = GND
  DC54  DDR7_SA_ECC4  BI  = M_H_CPU0_SA_CB<4>
  DC56  DDR7_SA_ECC1  BI  = M_H_CPU0_SA_CB<1>
  DC58  VSS738  POWER  = GND
  DC60  DDR7_SA_DQ28  BI  = M_H_CPU0_SA_DQ<28>
  DC62  DDR7_SA_DQ25  BI  = M_H_CPU0_SA_DQ<25>
  DC64  VSS739  POWER  = GND
  DC66  DDR7_SA_DQ20  BI  = M_H_CPU0_SA_DQ<20>
  DC68  DDR7_SA_DQ17  BI  = M_H_CPU0_SA_DQ<17>
  DC70  VSS954  POWER  = GND
  DC72  DDR7_SA_DQ12  BI  = M_H_CPU0_SA_DQ<12>
  DC74  DDR7_SA_DQ9  BI  = M_H_CPU0_SA_DQ<9>
  DC76  VSS956  POWER  = GND
  DC78  VSS958  POWER  = GND
  DC80  VSS960  POWER  = GND
  DC82  UPI3_RX_DN14  IN  = GND
  DC84  VSS961  POWER  = GND
  DC86  PE3_TX_DP11  OUT  = P5E_CPU0_PE3_TX_DP<11>
  DC88  VSS962  POWER  = GND
  DC90  PE3_RX_DP12  IN  = P5E_CPU0_PE3_RX_DP<12>
  DD2  UPI1_RX_DN12  IN  = UPI_CPU1_CPU0_P0P1_DP<12>
  DD4  VSS964  POWER  = GND
  DD6  UPI1_TX_DN11  OUT  = UPI_CPU0_CPU1_P1P0_DP<11>
  DD8  VSS967  POWER  = GND
  DD10  PE2_RX_DN3  IN  = P5E_CPU0_PE2_RX_DN<3>
  DD12  VSS747  POWER  = GND
  DD14  PE2_TX_DP4  OUT  = P5E_CPU0_PE2_TX_DP<4>
  DD16  VSS748  POWER  = GND
  DD18  DDR7_SB_DQS_DP3  BI  = M_H_CPU0_SB_DQS_DP<3>
  DD20  DDR7_SB_DQ24  BI  = M_H_CPU0_SB_DQ<24>
  DD22  DDR7_SB_DQ13  BI  = M_H_CPU0_SB_DQ<13>
  DD24  DDR7_SB_DQS_DN1  BI  = M_H_CPU0_SB_DQS_DN<1>
  DD26  DDR7_SB_DQ8  BI  = M_H_CPU0_SB_DQ<8>
  DD28  DDR7_SB_DQ7  BI  = M_H_CPU0_SB_DQ<7>
  DD30  DDR7_SB_DQS_DN0  BI  = M_H_CPU0_SB_DQS_DN<0>
  DD32  DDR7_SB_DQ0  BI  = M_H_CPU0_SB_DQ<0>
  DD34  DDR7_SB_ECC1  BI  = M_H_CPU0_SB_CB<1>
  DD36  DDR7_SB_DQS_DN9  BI  = M_H_CPU0_SB_DQS_DN<9>
  DD38  DDR7_SB_ECC6  BI  = M_H_CPU0_SB_CB<6>
  DD40  DDR7_SA_PAR  OUT  = M_H_CPU0_SA_PAR
  DD42  DDR7_CLK_DN1  OUT  = M_H_CPU0_CLK_DN<1>
  DD44  DDR4_A_RSP0  IN  = M_E_CPU0_SA_RSP<0>
  DD47  DDR7_SA_CA4  OUT  = M_H_CPU0_SA_CA<4>
  DD49  VSS753  POWER  = GND
  DD51  DDR7_SA_CS_N2  OUT  = M_H_CPU0_SA_CS_N<2>
  DD53  DDR7_SA_ECC5  BI  = M_H_CPU0_SA_CB<5>
  DD55  DDR7_SA_DQS_DN4  BI  = M_H_CPU0_SA_DQS_DN<4>
  DD57  DDR7_SA_ECC0  BI  = M_H_CPU0_SA_CB<0>
  DD59  DDR7_SA_DQ29  BI  = M_H_CPU0_SA_DQ<29>
  DD61  DDR7_SA_DQS_DN3  BI  = M_H_CPU0_SA_DQS_DN<3>
  DD63  DDR7_SA_DQ24  BI  = M_H_CPU0_SA_DQ<24>
  DD65  DDR7_SA_DQ21  BI  = M_H_CPU0_SA_DQ<21>
  DD67  DDR7_SA_DQS_DN2  BI  = M_H_CPU0_SA_DQS_DN<2>
  DD69  DDR7_SA_DQ16  BI  = M_H_CPU0_SA_DQ<16>
  DD71  DDR7_SA_DQ13  BI  = M_H_CPU0_SA_DQ<13>
  DD73  DDR7_SA_DQS_DP1  BI  = M_H_CPU0_SA_DQS_DP<1>
  DD75  DDR7_SA_DQ8  BI  = M_H_CPU0_SA_DQ<8>
  DD77  VCCFA_EHV_FIVRA46  POWER  = PVCCFA_EHV_FIVRA_CPU0
  DD79  VSS965  POWER  = GND
  DD81  UPI3_RX_DP15  IN  = GND
  DD83  VCCFA_EHV_FIVRA47  POWER  = PVCCFA_EHV_FIVRA_CPU0
  DD85  VCCFA_EHV_FIVRA48  POWER  = PVCCFA_EHV_FIVRA_CPU0
  DD87  PE3_TX_DN10  OUT  = P5E_CPU0_PE3_TX_DN<10>
  DD89  VCCFA_EHV_FIVRA49  POWER  = PVCCFA_EHV_FIVRA_CPU0
  DD91  PE3_RX_DN11  IN  = P5E_CPU0_PE3_RX_DN<11>
  DE1  UPI1_RX_DN11  IN  = UPI_CPU1_CPU0_P0P1_DN<11>
  DE3  VCCINFAON29  POWER  = PVCCINFAON_CPU0
  DE5  UPI1_TX_DN10  OUT  = UPI_CPU0_CPU1_P1P0_DP<10>
  DE7  VCCINFAON58  POWER  = PVCCINFAON_CPU0
  DE9  PE2_RX_DN4  IN  = P5E_CPU0_PE2_RX_DN<4>
  DE11  VCCINFAON27  POWER  = PVCCINFAON_CPU0
  DE13  PE2_TX_DN4  OUT  = P5E_CPU0_PE2_TX_DN<4>
  DE15  VCCINFAON28  POWER  = PVCCINFAON_CPU0
  DE17  VSS970  POWER  = GND
  DE19  VSS971  POWER  = GND
  DE21  VSS972  POWER  = GND
  DE23  VSS974  POWER  = GND
  DE25  VSS975  POWER  = GND
  DE27  VSS977  POWER  = GND
  DE29  VSS978  POWER  = GND
  DE31  VSS981  POWER  = GND
  DE33  VSS982  POWER  = GND
  DE35  VSS983  POWER  = GND
  DE37  VSS984  POWER  = GND
  DE39  VSS776  POWER  = GND
  DE41  VSS986  POWER  = GND
  DE43  VSS987  POWER  = GND
  DE45  VSS988  POWER  = GND
  DE48  VSS989  POWER  = GND
  DE50  VSS991  POWER  = GND
  DE52  VSS992  POWER  = GND
  DE54  VSS994  POWER  = GND
  DE56  VSS995  POWER  = GND
  DE58  VSS996  POWER  = GND
  DE60  VSS997  POWER  = GND
  DE62  VSS999  POWER  = GND
  DE64  VSS1001  POWER  = GND
  DE66  VSS1004  POWER  = GND
  DE68  VSS1007  POWER  = GND
  DE70  VSS791  POWER  = GND
  DE72  VSS1008  POWER  = GND
  DE74  VSS1009  POWER  = GND
  DE76  VSS1010  POWER  = GND
